(kicad_pcb
	(version 20260206)
	(generator "pcbnew")
	(generator_version "10.0")
	(general
		(thickness 1.6)
		(legacy_teardrops no)
	)
	(paper "A4")
	(title_block
		(title "03242023_DA0F0TMBIJ0_F0T_Motherboard_J_brd_V01_OCP.brd")
		(comment 1 "Grand Teton / footprints 2378-2383 of 6105")
	)
	(layers
		(0 "F.Cu" signal "TOP")
		(4 "In1.Cu" signal "GND")
		(6 "In2.Cu" signal "IN1")
		(8 "In3.Cu" signal "GND1")
		(10 "In4.Cu" signal "IN2")
		(12 "In5.Cu" signal "GND2")
		(14 "In6.Cu" signal "IN3")
		(16 "In7.Cu" signal "GND3")
		(18 "In8.Cu" signal "VCC")
		(20 "In9.Cu" signal "VCC1")
		(22 "In10.Cu" signal "GND4")
		(24 "In11.Cu" signal "IN4")
		(26 "In12.Cu" signal "GND5")
		(28 "In13.Cu" signal "IN5")
		(30 "In14.Cu" signal "GND6")
		(32 "In15.Cu" signal "IN6")
		(34 "In16.Cu" signal "GND7")
		(2 "B.Cu" signal "BOTTOM")
		(9 "F.Adhes" user "F.Adhesive")
		(11 "B.Adhes" user "B.Adhesive")
		(13 "F.Paste" user "Package Geometry/Pastemask Top")
		(15 "B.Paste" user "Package Geometry/Pastemask Bottom")
		(5 "F.SilkS" user "Ref Des/Silkscreen Top")
		(7 "B.SilkS" user "Ref Des/Silkscreen Bottom")
		(1 "F.Mask" user "Board Geometry/Soldermask Top")
		(3 "B.Mask" user "Board Geometry/Soldermask Bottom")
		(17 "Dwgs.User" user "User.Drawings")
		(19 "Cmts.User" user "User.Comments")
		(21 "Eco1.User" user "User.Eco1")
		(23 "Eco2.User" user "User.Eco2")
		(25 "Edge.Cuts" user "Board Geometry/Outline")
		(27 "Margin" user)
		(31 "F.CrtYd" user "Package Geometry/Place Bound Top")
		(29 "B.CrtYd" user "Package Geometry/Place Bound Bottom")
		(35 "F.Fab" user "Ref Des/Assembly Top")
		(33 "B.Fab" user "Ref Des/Assembly Bottom")
	)
	(footprint ""
		(layer "F.Cu")
		(at 117.098826 -315.66739 90)
		(property "Reference" "PC583"
			(at 0 0 90)
			(layer "F.SilkS")
			(hide yes)
			(effects
				(font
					(size 1.27 1.27)
				)
			)
		)
		(property "Value" ""
			(at 0 0 90)
			(layer "F.Fab")
			(effects
				(font
					(size 1.27 1.27)
				)
			)
		)
		(duplicate_pad_numbers_are_jumpers no)
		(fp_line
			(start 2.750058 0.999998)
			(end -2.750058 0.999998)
			(stroke
				(width 0.1524)
				(type default)
			)
			(layer "F.SilkS")
		)
		(fp_circle
			(center 0 0.999998)
			(end 0 3.750056)
			(stroke
				(width 0.1524)
				(type default)
			)
			(fill no)
			(layer "F.SilkS")
		)
		(fp_poly
			(pts
				(arc
					(start 2.750058 0.999998)
					(mid 0 3.750056)
					(end -2.750058 0.999998)
				)
			)
			(stroke
				(width 0)
				(type default)
			)
			(fill yes)
			(layer "F.SilkS")
		)
		(fp_circle
			(center 0 0.999998)
			(end 0 3.750056)
			(stroke
				(width 0.1)
				(type default)
			)
			(fill no)
			(layer "F.Fab")
		)
		(pad "1" thru_hole rect
			(at 0 0 90)
			(size 1.5748 1.5748)
			(drill 1.0668)
			(layers "*.Cu" "*.Mask")
			(remove_unused_layers no)
			(net "PVCCIN_CPU1")
			(clearance 0)
			(padstack
				(mode front_inner_back)
				(layer "Inner"
					(shape circle)
					(size 1.5748 1.5748)
					(clearance 0)
				)
				(layer "B.Cu"
					(shape rect)
					(size 1.5748 1.5748)
					(clearance 0)
				)
			)
		)
		(pad "2" thru_hole circle
			(at 0 1.999996 90)
			(size 1.5748 1.5748)
			(drill 1.0668)
			(layers "*.Cu" "*.Mask")
			(remove_unused_layers no)
			(net "GND")
			(clearance 0)
		)
	)
	(footprint ""
		(layer "F.Cu")
		(at 114.68608 -122.132598 90)
		(property "Reference" "C2252"
			(at 0 0 90)
			(layer "F.SilkS")
			(hide yes)
			(effects
				(font
					(size 1.27 1.27)
				)
			)
		)
		(property "Value" ""
			(at 0 0 90)
			(layer "F.Fab")
			(effects
				(font
					(size 1.27 1.27)
				)
			)
		)
		(duplicate_pad_numbers_are_jumpers no)
		(fp_line
			(start 0.7874 -0.4064)
			(end 0.7874 0.4064)
			(stroke
				(width 0.1524)
				(type default)
			)
			(layer "F.SilkS")
		)
		(fp_line
			(start -0.7874 -0.4064)
			(end 0.7874 -0.4064)
			(stroke
				(width 0.1524)
				(type default)
			)
			(layer "F.SilkS")
		)
		(fp_line
			(start 0.7874 0.4064)
			(end -0.7874 0.4064)
			(stroke
				(width 0.1524)
				(type default)
			)
			(layer "F.SilkS")
		)
		(fp_line
			(start -0.7874 0.4064)
			(end -0.7874 -0.4064)
			(stroke
				(width 0.1524)
				(type default)
			)
			(layer "F.SilkS")
		)
		(fp_line
			(start -0.12065 -0.305054)
			(end -0.12065 -0.2794)
			(stroke
				(width 0.1)
				(type default)
			)
			(layer "F.Fab")
		)
		(fp_line
			(start -0.67945 -0.305054)
			(end -0.12065 -0.305054)
			(stroke
				(width 0.1)
				(type default)
			)
			(layer "F.Fab")
		)
		(fp_line
			(start 0.67945 -0.3048)
			(end 0.67945 0.3048)
			(stroke
				(width 0.1)
				(type default)
			)
			(layer "F.Fab")
		)
		(fp_line
			(start 0.12065 -0.3048)
			(end 0.67945 -0.3048)
			(stroke
				(width 0.1)
				(type default)
			)
			(layer "F.Fab")
		)
		(fp_line
			(start 0.12065 -0.2794)
			(end 0.12065 -0.3048)
			(stroke
				(width 0.1)
				(type default)
			)
			(layer "F.Fab")
		)
		(fp_line
			(start -0.12065 -0.2794)
			(end 0.12065 -0.2794)
			(stroke
				(width 0.1)
				(type default)
			)
			(layer "F.Fab")
		)
		(fp_line
			(start 0.120396 0.2794)
			(end -0.12065 0.2794)
			(stroke
				(width 0.1)
				(type default)
			)
			(layer "F.Fab")
		)
		(fp_line
			(start -0.12065 0.2794)
			(end -0.12065 0.3048)
			(stroke
				(width 0.1)
				(type default)
			)
			(layer "F.Fab")
		)
		(fp_line
			(start 0.67945 0.3048)
			(end 0.120396 0.3048)
			(stroke
				(width 0.1)
				(type default)
			)
			(layer "F.Fab")
		)
		(fp_line
			(start 0.120396 0.3048)
			(end 0.120396 0.2794)
			(stroke
				(width 0.1)
				(type default)
			)
			(layer "F.Fab")
		)
		(fp_line
			(start -0.12065 0.3048)
			(end -0.67945 0.3048)
			(stroke
				(width 0.1)
				(type default)
			)
			(layer "F.Fab")
		)
		(fp_line
			(start -0.67945 0.3048)
			(end -0.67945 -0.305054)
			(stroke
				(width 0.1)
				(type default)
			)
			(layer "F.Fab")
		)
		(pad "1" smd circle
			(at -0.40005 0 90)
			(size 0 0)
			(layers "F.Cu" "F.Mask" "F.Paste")
			(net "P0V62_CPU0_RST_DDR_VREF")
		)
		(pad "2" smd circle
			(at 0.40005 0 90)
			(size 0 0)
			(layers "F.Cu" "F.Mask" "F.Paste")
			(net "GND")
		)
	)
	(footprint ""
		(layer "F.Cu")
		(at 128.401572 -131.018026)
		(property "Reference" "R2566"
			(at 0 0 0)
			(layer "F.SilkS")
			(hide yes)
			(effects
				(font
					(size 1.27 1.27)
				)
			)
		)
		(property "Value" ""
			(at 0 0 0)
			(layer "F.Fab")
			(effects
				(font
					(size 1.27 1.27)
				)
			)
		)
		(duplicate_pad_numbers_are_jumpers no)
		(fp_line
			(start -0.7874 -0.4064)
			(end 0.7874 -0.4064)
			(stroke
				(width 0.1524)
				(type default)
			)
			(layer "F.SilkS")
		)
		(fp_line
			(start -0.7874 0.4064)
			(end -0.7874 -0.4064)
			(stroke
				(width 0.1524)
				(type default)
			)
			(layer "F.SilkS")
		)
		(fp_line
			(start 0.7874 -0.4064)
			(end 0.7874 0.4064)
			(stroke
				(width 0.1524)
				(type default)
			)
			(layer "F.SilkS")
		)
		(fp_line
			(start 0.7874 0.4064)
			(end -0.7874 0.4064)
			(stroke
				(width 0.1524)
				(type default)
			)
			(layer "F.SilkS")
		)
		(fp_line
			(start -0.67945 -0.305054)
			(end -0.12065 -0.305054)
			(stroke
				(width 0.1)
				(type default)
			)
			(layer "F.Fab")
		)
		(fp_line
			(start -0.67945 0.3048)
			(end -0.67945 -0.305054)
			(stroke
				(width 0.1)
				(type default)
			)
			(layer "F.Fab")
		)
		(fp_line
			(start -0.12065 -0.305054)
			(end -0.12065 -0.2794)
			(stroke
				(width 0.1)
				(type default)
			)
			(layer "F.Fab")
		)
		(fp_line
			(start -0.12065 -0.2794)
			(end 0.12065 -0.2794)
			(stroke
				(width 0.1)
				(type default)
			)
			(layer "F.Fab")
		)
		(fp_line
			(start -0.12065 0.2794)
			(end -0.12065 0.3048)
			(stroke
				(width 0.1)
				(type default)
			)
			(layer "F.Fab")
		)
		(fp_line
			(start -0.12065 0.3048)
			(end -0.67945 0.3048)
			(stroke
				(width 0.1)
				(type default)
			)
			(layer "F.Fab")
		)
		(fp_line
			(start 0.120396 0.2794)
			(end -0.12065 0.2794)
			(stroke
				(width 0.1)
				(type default)
			)
			(layer "F.Fab")
		)
		(fp_line
			(start 0.120396 0.3048)
			(end 0.120396 0.2794)
			(stroke
				(width 0.1)
				(type default)
			)
			(layer "F.Fab")
		)
		(fp_line
			(start 0.12065 -0.3048)
			(end 0.67945 -0.3048)
			(stroke
				(width 0.1)
				(type default)
			)
			(layer "F.Fab")
		)
		(fp_line
			(start 0.12065 -0.2794)
			(end 0.12065 -0.3048)
			(stroke
				(width 0.1)
				(type default)
			)
			(layer "F.Fab")
		)
		(fp_line
			(start 0.67945 -0.3048)
			(end 0.67945 0.3048)
			(stroke
				(width 0.1)
				(type default)
			)
			(layer "F.Fab")
		)
		(fp_line
			(start 0.67945 0.3048)
			(end 0.120396 0.3048)
			(stroke
				(width 0.1)
				(type default)
			)
			(layer "F.Fab")
		)
		(pad "1" smd circle
			(at -0.40005 0)
			(size 0 0)
			(layers "F.Cu" "F.Mask" "F.Paste")
			(net "SMB_FRU_3V3AUX_SDA_R")
		)
		(pad "2" smd circle
			(at 0.40005 0)
			(size 0 0)
			(layers "F.Cu" "F.Mask" "F.Paste")
			(net "SMB_FRU_3V3AUX_SDA")
		)
	)
	(footprint ""
		(layer "F.Cu")
		(at 44.467018 -439.824368 -90)
		(property "Reference" "R2986"
			(at 0 0 270)
			(layer "F.SilkS")
			(hide yes)
			(effects
				(font
					(size 1.27 1.27)
				)
			)
		)
		(property "Value" ""
			(at 0 0 270)
			(layer "F.Fab")
			(effects
				(font
					(size 1.27 1.27)
				)
			)
		)
		(duplicate_pad_numbers_are_jumpers no)
		(fp_line
			(start -0.7874 0.4064)
			(end -0.7874 -0.4064)
			(stroke
				(width 0.1524)
				(type default)
			)
			(layer "F.SilkS")
		)
		(fp_line
			(start 0.7874 0.4064)
			(end -0.7874 0.4064)
			(stroke
				(width 0.1524)
				(type default)
			)
			(layer "F.SilkS")
		)
		(fp_line
			(start -0.7874 -0.4064)
			(end 0.7874 -0.4064)
			(stroke
				(width 0.1524)
				(type default)
			)
			(layer "F.SilkS")
		)
		(fp_line
			(start 0.7874 -0.4064)
			(end 0.7874 0.4064)
			(stroke
				(width 0.1524)
				(type default)
			)
			(layer "F.SilkS")
		)
		(fp_line
			(start -0.67945 0.3048)
			(end -0.67945 -0.305054)
			(stroke
				(width 0.1)
				(type default)
			)
			(layer "F.Fab")
		)
		(fp_line
			(start -0.12065 0.3048)
			(end -0.67945 0.3048)
			(stroke
				(width 0.1)
				(type default)
			)
			(layer "F.Fab")
		)
		(fp_line
			(start 0.120396 0.3048)
			(end 0.120396 0.2794)
			(stroke
				(width 0.1)
				(type default)
			)
			(layer "F.Fab")
		)
		(fp_line
			(start 0.67945 0.3048)
			(end 0.120396 0.3048)
			(stroke
				(width 0.1)
				(type default)
			)
			(layer "F.Fab")
		)
		(fp_line
			(start -0.12065 0.2794)
			(end -0.12065 0.3048)
			(stroke
				(width 0.1)
				(type default)
			)
			(layer "F.Fab")
		)
		(fp_line
			(start 0.120396 0.2794)
			(end -0.12065 0.2794)
			(stroke
				(width 0.1)
				(type default)
			)
			(layer "F.Fab")
		)
		(fp_line
			(start -0.12065 -0.2794)
			(end 0.12065 -0.2794)
			(stroke
				(width 0.1)
				(type default)
			)
			(layer "F.Fab")
		)
		(fp_line
			(start 0.12065 -0.2794)
			(end 0.12065 -0.3048)
			(stroke
				(width 0.1)
				(type default)
			)
			(layer "F.Fab")
		)
		(fp_line
			(start 0.12065 -0.3048)
			(end 0.67945 -0.3048)
			(stroke
				(width 0.1)
				(type default)
			)
			(layer "F.Fab")
		)
		(fp_line
			(start 0.67945 -0.3048)
			(end 0.67945 0.3048)
			(stroke
				(width 0.1)
				(type default)
			)
			(layer "F.Fab")
		)
		(fp_line
			(start -0.67945 -0.305054)
			(end -0.12065 -0.305054)
			(stroke
				(width 0.1)
				(type default)
			)
			(layer "F.Fab")
		)
		(fp_line
			(start -0.12065 -0.305054)
			(end -0.12065 -0.2794)
			(stroke
				(width 0.1)
				(type default)
			)
			(layer "F.Fab")
		)
		(pad "1" smd circle
			(at -0.40005 0 270)
			(size 0 0)
			(layers "F.Cu" "F.Mask" "F.Paste")
			(net "SMB_2_BMC_GPU_R_SCL")
		)
		(pad "2" smd circle
			(at 0.40005 0 270)
			(size 0 0)
			(layers "F.Cu" "F.Mask" "F.Paste")
			(net "SMB_2_BMC_GPU_BUF_R_SCL")
		)
	)
	(footprint ""
		(layer "F.Cu")
		(at 416.097974 -158.61665 180)
		(property "Reference" "PC634"
			(at 0 0 180)
			(layer "F.SilkS")
			(hide yes)
			(effects
				(font
					(size 1.27 1.27)
				)
			)
		)
		(property "Value" ""
			(at 0 0 180)
			(layer "F.Fab")
			(effects
				(font
					(size 1.27 1.27)
				)
			)
		)
		(duplicate_pad_numbers_are_jumpers no)
		(fp_line
			(start 0.7874 0.4064)
			(end -0.7874 0.4064)
			(stroke
				(width 0.1524)
				(type default)
			)
			(layer "F.SilkS")
		)
		(fp_line
			(start 0.7874 -0.4064)
			(end 0.7874 0.4064)
			(stroke
				(width 0.1524)
				(type default)
			)
			(layer "F.SilkS")
		)
		(fp_line
			(start -0.7874 0.4064)
			(end -0.7874 -0.4064)
			(stroke
				(width 0.1524)
				(type default)
			)
			(layer "F.SilkS")
		)
		(fp_line
			(start -0.7874 -0.4064)
			(end 0.7874 -0.4064)
			(stroke
				(width 0.1524)
				(type default)
			)
			(layer "F.SilkS")
		)
		(fp_line
			(start 0.67945 0.3048)
			(end 0.120396 0.3048)
			(stroke
				(width 0.1)
				(type default)
			)
			(layer "F.Fab")
		)
		(fp_line
			(start 0.67945 -0.3048)
			(end 0.67945 0.3048)
			(stroke
				(width 0.1)
				(type default)
			)
			(layer "F.Fab")
		)
		(fp_line
			(start 0.12065 -0.2794)
			(end 0.12065 -0.3048)
			(stroke
				(width 0.1)
				(type default)
			)
			(layer "F.Fab")
		)
		(fp_line
			(start 0.12065 -0.3048)
			(end 0.67945 -0.3048)
			(stroke
				(width 0.1)
				(type default)
			)
			(layer "F.Fab")
		)
		(fp_line
			(start 0.120396 0.3048)
			(end 0.120396 0.2794)
			(stroke
				(width 0.1)
				(type default)
			)
			(layer "F.Fab")
		)
		(fp_line
			(start 0.120396 0.2794)
			(end -0.12065 0.2794)
			(stroke
				(width 0.1)
				(type default)
			)
			(layer "F.Fab")
		)
		(fp_line
			(start -0.12065 0.3048)
			(end -0.67945 0.3048)
			(stroke
				(width 0.1)
				(type default)
			)
			(layer "F.Fab")
		)
		(fp_line
			(start -0.12065 0.2794)
			(end -0.12065 0.3048)
			(stroke
				(width 0.1)
				(type default)
			)
			(layer "F.Fab")
		)
		(fp_line
			(start -0.12065 -0.2794)
			(end 0.12065 -0.2794)
			(stroke
				(width 0.1)
				(type default)
			)
			(layer "F.Fab")
		)
		(fp_line
			(start -0.12065 -0.305054)
			(end -0.12065 -0.2794)
			(stroke
				(width 0.1)
				(type default)
			)
			(layer "F.Fab")
		)
		(fp_line
			(start -0.67945 0.3048)
			(end -0.67945 -0.305054)
			(stroke
				(width 0.1)
				(type default)
			)
			(layer "F.Fab")
		)
		(fp_line
			(start -0.67945 -0.305054)
			(end -0.12065 -0.305054)
			(stroke
				(width 0.1)
				(type default)
			)
			(layer "F.Fab")
		)
		(pad "1" smd circle
			(at -0.40005 0 180)
			(size 0 0)
			(layers "F.Cu" "F.Mask" "F.Paste")
			(net "SW_P12V_PVCCINFAON_CPU0_FLT")
		)
		(pad "2" smd circle
			(at 0.40005 0 180)
			(size 0 0)
			(layers "F.Cu" "F.Mask" "F.Paste")
			(net "GND")
		)
	)
	(footprint ""
		(layer "F.Cu")
		(at 280.278078 -417.2839 90)
		(property "Reference" "R4667"
			(at 0 0 90)
			(layer "F.SilkS")
			(hide yes)
			(effects
				(font
					(size 1.27 1.27)
				)
			)
		)
		(property "Value" ""
			(at 0 0 90)
			(layer "F.Fab")
			(effects
				(font
					(size 1.27 1.27)
				)
			)
		)
		(duplicate_pad_numbers_are_jumpers no)
		(fp_line
			(start 0.7874 -0.4064)
			(end 0.7874 0.4064)
			(stroke
				(width 0.1524)
				(type default)
			)
			(layer "F.SilkS")
		)
		(fp_line
			(start -0.7874 -0.4064)
			(end 0.7874 -0.4064)
			(stroke
				(width 0.1524)
				(type default)
			)
			(layer "F.SilkS")
		)
		(fp_line
			(start 0.7874 0.4064)
			(end -0.7874 0.4064)
			(stroke
				(width 0.1524)
				(type default)
			)
			(layer "F.SilkS")
		)
		(fp_line
			(start -0.7874 0.4064)
			(end -0.7874 -0.4064)
			(stroke
				(width 0.1524)
				(type default)
			)
			(layer "F.SilkS")
		)
		(fp_line
			(start -0.12065 -0.305054)
			(end -0.12065 -0.2794)
			(stroke
				(width 0.1)
				(type default)
			)
			(layer "F.Fab")
		)
		(fp_line
			(start -0.67945 -0.305054)
			(end -0.12065 -0.305054)
			(stroke
				(width 0.1)
				(type default)
			)
			(layer "F.Fab")
		)
		(fp_line
			(start 0.67945 -0.3048)
			(end 0.67945 0.3048)
			(stroke
				(width 0.1)
				(type default)
			)
			(layer "F.Fab")
		)
		(fp_line
			(start 0.12065 -0.3048)
			(end 0.67945 -0.3048)
			(stroke
				(width 0.1)
				(type default)
			)
			(layer "F.Fab")
		)
		(fp_line
			(start 0.12065 -0.2794)
			(end 0.12065 -0.3048)
			(stroke
				(width 0.1)
				(type default)
			)
			(layer "F.Fab")
		)
		(fp_line
			(start -0.12065 -0.2794)
			(end 0.12065 -0.2794)
			(stroke
				(width 0.1)
				(type default)
			)
			(layer "F.Fab")
		)
		(fp_line
			(start 0.120396 0.2794)
			(end -0.12065 0.2794)
			(stroke
				(width 0.1)
				(type default)
			)
			(layer "F.Fab")
		)
		(fp_line
			(start -0.12065 0.2794)
			(end -0.12065 0.3048)
			(stroke
				(width 0.1)
				(type default)
			)
			(layer "F.Fab")
		)
		(fp_line
			(start 0.67945 0.3048)
			(end 0.120396 0.3048)
			(stroke
				(width 0.1)
				(type default)
			)
			(layer "F.Fab")
		)
		(fp_line
			(start 0.120396 0.3048)
			(end 0.120396 0.2794)
			(stroke
				(width 0.1)
				(type default)
			)
			(layer "F.Fab")
		)
		(fp_line
			(start -0.12065 0.3048)
			(end -0.67945 0.3048)
			(stroke
				(width 0.1)
				(type default)
			)
			(layer "F.Fab")
		)
		(fp_line
			(start -0.67945 0.3048)
			(end -0.67945 -0.305054)
			(stroke
				(width 0.1)
				(type default)
			)
			(layer "F.Fab")
		)
		(pad "1" smd circle
			(at -0.40005 0 90)
			(size 0 0)
			(layers "F.Cu" "F.Mask" "F.Paste")
			(net "HSC_CSOUT")
		)
		(pad "2" smd circle
			(at 0.40005 0 90)
			(size 0 0)
			(layers "F.Cu" "F.Mask" "F.Paste")
			(net "A_HSC_LOW")
		)
	)
)
